# S9S_MB_2U (Grand Teton) — schematic netlist excerpt (pin names and nets, part order shuffled) for the footprints in the layout excerpt that follows; sources: Cadence DE-HDL packaged netlist, KiCad conversion of 03242023_DA0F0TMBIJ0_F0T_Motherboard_J_brd_V01_OCP.brd

D141  SCHOTTKY_12  1N5819HW IC  pkg SOD123  page 221 : A = P3V3_AUX ; C = P3V3_AUX_BMC_D
R3494  Q_RES  54.9K 1% CHIP  pkg 0402LF  page 150 : A = P3V3_AUX ; B = GPU_FPGA_EROT_RECOV_BUF_R_N

(kicad_pcb
	(version 20260206)
	(generator "pcbnew")
	(generator_version "10.0")
	(general
		(thickness 1.6)
		(legacy_teardrops no)
	)
	(paper "A4")
	(title_block
		(title "03242023_DA0F0TMBIJ0_F0T_Motherboard_J_brd_V01_OCP.brd")
		(comment 1 "Grand Teton / footprints 2498-2499 of 6105")
	)
	(layers
		(0 "F.Cu" signal "TOP")
		(4 "In1.Cu" signal "GND")
		(6 "In2.Cu" signal "IN1")
		(8 "In3.Cu" signal "GND1")
		(10 "In4.Cu" signal "IN2")
		(12 "In5.Cu" signal "GND2")
		(14 "In6.Cu" signal "IN3")
		(16 "In7.Cu" signal "GND3")
		(18 "In8.Cu" signal "VCC")
		(20 "In9.Cu" signal "VCC1")
		(22 "In10.Cu" signal "GND4")
		(24 "In11.Cu" signal "IN4")
		(26 "In12.Cu" signal "GND5")
		(28 "In13.Cu" signal "IN5")
		(30 "In14.Cu" signal "GND6")
		(32 "In15.Cu" signal "IN6")
		(34 "In16.Cu" signal "GND7")
		(2 "B.Cu" signal "BOTTOM")
		(9 "F.Adhes" user "F.Adhesive")
		(11 "B.Adhes" user "B.Adhesive")
		(13 "F.Paste" user "Package Geometry/Pastemask Top")
		(15 "B.Paste" user "Package Geometry/Pastemask Bottom")
		(5 "F.SilkS" user "Ref Des/Silkscreen Top")
		(7 "B.SilkS" user "Ref Des/Silkscreen Bottom")
		(1 "F.Mask" user "Board Geometry/Soldermask Top")
		(3 "B.Mask" user "Board Geometry/Soldermask Bottom")
		(17 "Dwgs.User" user "User.Drawings")
		(19 "Cmts.User" user "User.Comments")
		(21 "Eco1.User" user "User.Eco1")
		(23 "Eco2.User" user "User.Eco2")
		(25 "Edge.Cuts" user "Board Geometry/Outline")
		(27 "Margin" user)
		(31 "F.CrtYd" user "Package Geometry/Place Bound Top")
		(29 "B.CrtYd" user "Package Geometry/Place Bound Bottom")
		(35 "F.Fab" user "Ref Des/Assembly Top")
		(33 "B.Fab" user "Ref Des/Assembly Bottom")
	)
	(footprint ""
		(layer "F.Cu")
		(at 131.68122 -75.85837 -90)
		(property "Reference" "D141"
			(at -4.793488 -2.42316 0)
			(unlocked yes)
			(layer "F.SilkS")
			(effects
				(font
					(size 0.7874 0.5842)
					(thickness 0.1524)
				)
				(justify left)
			)
		)
		(property "Value" ""
			(at 0 0 270)
			(layer "F.Fab")
			(effects
				(font
					(size 1.27 1.27)
				)
			)
		)
		(duplicate_pad_numbers_are_jumpers no)
		(fp_line
			(start -2.4638 1.0414)
			(end -2.4638 -1.0414)
			(stroke
				(width 0.1524)
				(type default)
			)
			(layer "F.SilkS")
		)
		(fp_line
			(start 2.7178 1.0414)
			(end -2.4638 1.0414)
			(stroke
				(width 0.1524)
				(type default)
			)
			(layer "F.SilkS")
		)
		(fp_line
			(start -0.508 0.5334)
			(end 0.1778 -0.0254)
			(stroke
				(width 0.1524)
				(type default)
			)
			(layer "F.SilkS")
		)
		(fp_line
			(start 0.1778 -0.0254)
			(end -0.4826 -0.4826)
			(stroke
				(width 0.1524)
				(type default)
			)
			(layer "F.SilkS")
		)
		(fp_line
			(start -0.508 -0.508)
			(end -0.508 0.5334)
			(stroke
				(width 0.1524)
				(type default)
			)
			(layer "F.SilkS")
		)
		(fp_line
			(start 0.254 -0.508)
			(end 0.254 0.5334)
			(stroke
				(width 0.1524)
				(type default)
			)
			(layer "F.SilkS")
		)
		(fp_line
			(start -2.4638 -1.0414)
			(end 2.7178 -1.0414)
			(stroke
				(width 0.1524)
				(type default)
			)
			(layer "F.SilkS")
		)
		(fp_line
			(start 2.4638 -1.0414)
			(end 2.4638 1.0414)
			(stroke
				(width 0.1524)
				(type default)
			)
			(layer "F.SilkS")
		)
		(fp_line
			(start 2.5908 -1.0414)
			(end 2.5908 1.0414)
			(stroke
				(width 0.1524)
				(type default)
			)
			(layer "F.SilkS")
		)
		(fp_line
			(start 2.7178 -1.0414)
			(end 2.7178 1.0414)
			(stroke
				(width 0.1524)
				(type default)
			)
			(layer "F.SilkS")
		)
		(fp_line
			(start -2.4638 1.0414)
			(end -2.4638 -1.0414)
			(stroke
				(width 0.1)
				(type default)
			)
			(layer "F.Fab")
		)
		(fp_line
			(start 2.7178 1.0414)
			(end -2.4638 1.0414)
			(stroke
				(width 0.1)
				(type default)
			)
			(layer "F.Fab")
		)
		(fp_line
			(start -2.4638 -1.0414)
			(end 2.7178 -1.0414)
			(stroke
				(width 0.1)
				(type default)
			)
			(layer "F.Fab")
		)
		(fp_line
			(start 2.7178 -1.0414)
			(end 2.7178 1.0414)
			(stroke
				(width 0.1)
				(type default)
			)
			(layer "F.Fab")
		)
		(fp_text user "-"
			(at 2.538222 1.24841 270)
			(unlocked yes)
			(layer "F.SilkS")
			(effects
				(font
					(size 1.905 1.4224)
					(thickness 0.1524)
				)
				(justify left)
			)
		)
		(fp_text user "+"
			(at -3.9624 -0.17145 270)
			(unlocked yes)
			(layer "F.SilkS")
			(effects
				(font
					(size 1.905 1.4224)
					(thickness 0.1524)
				)
				(justify left)
			)
		)
		(fp_text user "+"
			(at -3.9624 -0.17145 270)
			(unlocked yes)
			(layer "F.Fab")
			(effects
				(font
					(size 1.905 1.4224)
					(thickness 0.1524)
				)
				(justify left)
			)
		)
		(fp_text user "-"
			(at 2.9845 -0.366268 270)
			(unlocked yes)
			(layer "F.Fab")
			(effects
				(font
					(size 1.905 1.4224)
					(thickness 0.1524)
				)
				(justify left)
			)
		)
		(pad "1" smd rect
			(at -1.724914 0 270)
			(size 1.1684 1.7526)
			(layers "F.Cu" "F.Mask" "F.Paste")
			(net "P3V3_AUX")
		)
		(pad "2" smd rect
			(at 1.724914 0 270)
			(size 1.1684 1.7526)
			(layers "F.Cu" "F.Mask" "F.Paste")
			(net "P3V3_AUX_BMC_D")
		)
	)
	(footprint ""
		(layer "F.Cu")
		(at 111.095282 -406.058116 -90)
		(property "Reference" "R3494"
			(at 0 0 270)
			(layer "F.SilkS")
			(hide yes)
			(effects
				(font
					(size 1.27 1.27)
				)
			)
		)
		(property "Value" ""
			(at 0 0 270)
			(layer "F.Fab")
			(effects
				(font
					(size 1.27 1.27)
				)
			)
		)
		(duplicate_pad_numbers_are_jumpers no)
		(fp_line
			(start -0.7874 0.4064)
			(end -0.7874 -0.4064)
			(stroke
				(width 0.1524)
				(type default)
			)
			(layer "F.SilkS")
		)
		(fp_line
			(start 0.7874 0.4064)
			(end -0.7874 0.4064)
			(stroke
				(width 0.1524)
				(type default)
			)
			(layer "F.SilkS")
		)
		(fp_line
			(start -0.7874 -0.4064)
			(end 0.7874 -0.4064)
			(stroke
				(width 0.1524)
				(type default)
			)
			(layer "F.SilkS")
		)
		(fp_line
			(start 0.7874 -0.4064)
			(end 0.7874 0.4064)
			(stroke
				(width 0.1524)
				(type default)
			)
			(layer "F.SilkS")
		)
		(fp_line
			(start -0.67945 0.3048)
			(end -0.67945 -0.305054)
			(stroke
				(width 0.1)
				(type default)
			)
			(layer "F.Fab")
		)
		(fp_line
			(start -0.12065 0.3048)
			(end -0.67945 0.3048)
			(stroke
				(width 0.1)
				(type default)
			)
			(layer "F.Fab")
		)
		(fp_line
			(start 0.120396 0.3048)
			(end 0.120396 0.2794)
			(stroke
				(width 0.1)
				(type default)
			)
			(layer "F.Fab")
		)
		(fp_line
			(start 0.67945 0.3048)
			(end 0.120396 0.3048)
			(stroke
				(width 0.1)
				(type default)
			)
			(layer "F.Fab")
		)
		(fp_line
			(start -0.12065 0.2794)
			(end -0.12065 0.3048)
			(stroke
				(width 0.1)
				(type default)
			)
			(layer "F.Fab")
		)
		(fp_line
			(start 0.120396 0.2794)
			(end -0.12065 0.2794)
			(stroke
				(width 0.1)
				(type default)
			)
			(layer "F.Fab")
		)
		(fp_line
			(start -0.12065 -0.2794)
			(end 0.12065 -0.2794)
			(stroke
				(width 0.1)
				(type default)
			)
			(layer "F.Fab")
		)
		(fp_line
			(start 0.12065 -0.2794)
			(end 0.12065 -0.3048)
			(stroke
				(width 0.1)
				(type default)
			)
			(layer "F.Fab")
		)
		(fp_line
			(start 0.12065 -0.3048)
			(end 0.67945 -0.3048)
			(stroke
				(width 0.1)
				(type default)
			)
			(layer "F.Fab")
		)
		(fp_line
			(start 0.67945 -0.3048)
			(end 0.67945 0.3048)
			(stroke
				(width 0.1)
				(type default)
			)
			(layer "F.Fab")
		)
		(fp_line
			(start -0.67945 -0.305054)
			(end -0.12065 -0.305054)
			(stroke
				(width 0.1)
				(type default)
			)
			(layer "F.Fab")
		)
		(fp_line
			(start -0.12065 -0.305054)
			(end -0.12065 -0.2794)
			(stroke
				(width 0.1)
				(type default)
			)
			(layer "F.Fab")
		)
		(pad "1" smd circle
			(at -0.40005 0 270)
			(size 0 0)
			(layers "F.Cu" "F.Mask" "F.Paste")
			(net "P3V3_AUX")
		)
		(pad "2" smd circle
			(at 0.40005 0 270)
			(size 0 0)
			(layers "F.Cu" "F.Mask" "F.Paste")
			(net "GPU_FPGA_EROT_RECOV_BUF_R_N")
		)
	)
)
